(kicad_pcb
	(version 20260206)
	(generator "pcbnew")
	(generator_version "10.0")
	(general
		(thickness 1.6)
		(legacy_teardrops no)
	)
	(paper "A4")
	(title_block
		(title "04192023_DAF0TMB3IC0_F0TG_MB_C_brd_V02_OCP.brd")
		(comment 1 "Grand Teton / footprints 7726-7733 of 8354")
	)
	(layers
		(0 "F.Cu" signal "TOP")
		(4 "In1.Cu" signal "GND")
		(6 "In2.Cu" signal "IN1")
		(8 "In3.Cu" signal "GND1")
		(10 "In4.Cu" signal "IN2")
		(12 "In5.Cu" signal "GND2")
		(14 "In6.Cu" signal "IN3")
		(16 "In7.Cu" signal "GND3")
		(18 "In8.Cu" signal "VCC")
		(20 "In9.Cu" signal "VCC1")
		(22 "In10.Cu" signal "GND4")
		(24 "In11.Cu" signal "IN4")
		(26 "In12.Cu" signal "GND5")
		(28 "In13.Cu" signal "IN5")
		(30 "In14.Cu" signal "GND6")
		(32 "In15.Cu" signal "IN6")
		(34 "In16.Cu" signal "GND7")
		(2 "B.Cu" signal "BOTTOM")
		(9 "F.Adhes" user "F.Adhesive")
		(11 "B.Adhes" user "B.Adhesive")
		(13 "F.Paste" user "Package Geometry/Pastemask Top")
		(15 "B.Paste" user "Package Geometry/Pastemask Bottom")
		(5 "F.SilkS" user "Ref Des/Silkscreen Top")
		(7 "B.SilkS" user "Ref Des/Silkscreen Bottom")
		(1 "F.Mask" user "Board Geometry/Soldermask Top")
		(3 "B.Mask" user "Board Geometry/Soldermask Bottom")
		(17 "Dwgs.User" user "User.Drawings")
		(19 "Cmts.User" user "User.Comments")
		(21 "Eco1.User" user "User.Eco1")
		(23 "Eco2.User" user "User.Eco2")
		(25 "Edge.Cuts" user "Board Geometry/Outline")
		(27 "Margin" user)
		(31 "F.CrtYd" user "Package Geometry/Place Bound Top")
		(29 "B.CrtYd" user "Package Geometry/Place Bound Bottom")
		(35 "F.Fab" user "Ref Des/Assembly Top")
		(33 "B.Fab" user "Ref Des/Assembly Bottom")
	)
	(footprint ""
		(layer "B.Cu")
		(at 160.218882 -390.560052 90)
		(property "Reference" "C416"
			(at 0 0 90)
			(layer "B.SilkS")
			(hide yes)
			(effects
				(font
					(size 1.27 1.27)
				)
				(justify mirror)
			)
		)
		(property "Value" ""
			(at 0 0 90)
			(layer "B.Fab")
			(effects
				(font
					(size 1.27 1.27)
				)
				(justify mirror)
			)
		)
		(duplicate_pad_numbers_are_jumpers no)
		(fp_line
			(start 0.7874 -0.4064)
			(end -0.7874 -0.4064)
			(stroke
				(width 0.1524)
				(type default)
			)
			(layer "B.SilkS")
		)
		(fp_line
			(start -0.7874 -0.4064)
			(end -0.7874 0.4064)
			(stroke
				(width 0.1524)
				(type default)
			)
			(layer "B.SilkS")
		)
		(fp_line
			(start 0.7874 0.4064)
			(end 0.7874 -0.4064)
			(stroke
				(width 0.1524)
				(type default)
			)
			(layer "B.SilkS")
		)
		(fp_line
			(start -0.7874 0.4064)
			(end 0.7874 0.4064)
			(stroke
				(width 0.1524)
				(type default)
			)
			(layer "B.SilkS")
		)
		(fp_line
			(start 0.67945 -0.305054)
			(end 0.12065 -0.305054)
			(stroke
				(width 0.1)
				(type default)
			)
			(layer "B.Fab")
		)
		(fp_line
			(start 0.12065 -0.305054)
			(end 0.12065 -0.2794)
			(stroke
				(width 0.1)
				(type default)
			)
			(layer "B.Fab")
		)
		(fp_line
			(start -0.12065 -0.3048)
			(end -0.67945 -0.3048)
			(stroke
				(width 0.1)
				(type default)
			)
			(layer "B.Fab")
		)
		(fp_line
			(start -0.67945 -0.3048)
			(end -0.67945 0.3048)
			(stroke
				(width 0.1)
				(type default)
			)
			(layer "B.Fab")
		)
		(fp_line
			(start 0.12065 -0.2794)
			(end -0.12065 -0.2794)
			(stroke
				(width 0.1)
				(type default)
			)
			(layer "B.Fab")
		)
		(fp_line
			(start -0.12065 -0.2794)
			(end -0.12065 -0.3048)
			(stroke
				(width 0.1)
				(type default)
			)
			(layer "B.Fab")
		)
		(fp_line
			(start 0.12065 0.2794)
			(end 0.12065 0.3048)
			(stroke
				(width 0.1)
				(type default)
			)
			(layer "B.Fab")
		)
		(fp_line
			(start -0.120396 0.2794)
			(end 0.12065 0.2794)
			(stroke
				(width 0.1)
				(type default)
			)
			(layer "B.Fab")
		)
		(fp_line
			(start 0.67945 0.3048)
			(end 0.67945 -0.305054)
			(stroke
				(width 0.1)
				(type default)
			)
			(layer "B.Fab")
		)
		(fp_line
			(start 0.12065 0.3048)
			(end 0.67945 0.3048)
			(stroke
				(width 0.1)
				(type default)
			)
			(layer "B.Fab")
		)
		(fp_line
			(start -0.120396 0.3048)
			(end -0.120396 0.2794)
			(stroke
				(width 0.1)
				(type default)
			)
			(layer "B.Fab")
		)
		(fp_line
			(start -0.67945 0.3048)
			(end -0.120396 0.3048)
			(stroke
				(width 0.1)
				(type default)
			)
			(layer "B.Fab")
		)
		(pad "1" smd circle
			(at 0.40005 0 270)
			(size 0 0)
			(layers "B.Cu" "B.Mask" "B.Paste")
			(net "P0V9_CPU1_RT2_2A")
		)
		(pad "2" smd circle
			(at -0.40005 0 270)
			(size 0 0)
			(layers "B.Cu" "B.Mask" "B.Paste")
			(net "GND")
		)
	)
	(footprint ""
		(layer "B.Cu")
		(at 341.079328 -336.083656 -90)
		(property "Reference" "PR94"
			(at 0 0 90)
			(layer "B.SilkS")
			(hide yes)
			(effects
				(font
					(size 1.27 1.27)
				)
				(justify mirror)
			)
		)
		(property "Value" ""
			(at 0 0 90)
			(layer "B.Fab")
			(effects
				(font
					(size 1.27 1.27)
				)
				(justify mirror)
			)
		)
		(duplicate_pad_numbers_are_jumpers no)
		(fp_line
			(start -0.7874 0.4064)
			(end 0.7874 0.4064)
			(stroke
				(width 0.1524)
				(type default)
			)
			(layer "B.SilkS")
		)
		(fp_line
			(start 0.7874 0.4064)
			(end 0.7874 -0.4064)
			(stroke
				(width 0.1524)
				(type default)
			)
			(layer "B.SilkS")
		)
		(fp_line
			(start -0.7874 -0.4064)
			(end -0.7874 0.4064)
			(stroke
				(width 0.1524)
				(type default)
			)
			(layer "B.SilkS")
		)
		(fp_line
			(start 0.7874 -0.4064)
			(end -0.7874 -0.4064)
			(stroke
				(width 0.1524)
				(type default)
			)
			(layer "B.SilkS")
		)
		(fp_line
			(start -0.67945 0.3048)
			(end -0.120396 0.3048)
			(stroke
				(width 0.1)
				(type default)
			)
			(layer "B.Fab")
		)
		(fp_line
			(start -0.120396 0.3048)
			(end -0.120396 0.2794)
			(stroke
				(width 0.1)
				(type default)
			)
			(layer "B.Fab")
		)
		(fp_line
			(start 0.12065 0.3048)
			(end 0.67945 0.3048)
			(stroke
				(width 0.1)
				(type default)
			)
			(layer "B.Fab")
		)
		(fp_line
			(start 0.67945 0.3048)
			(end 0.67945 -0.305054)
			(stroke
				(width 0.1)
				(type default)
			)
			(layer "B.Fab")
		)
		(fp_line
			(start -0.120396 0.2794)
			(end 0.12065 0.2794)
			(stroke
				(width 0.1)
				(type default)
			)
			(layer "B.Fab")
		)
		(fp_line
			(start 0.12065 0.2794)
			(end 0.12065 0.3048)
			(stroke
				(width 0.1)
				(type default)
			)
			(layer "B.Fab")
		)
		(fp_line
			(start -0.12065 -0.2794)
			(end -0.12065 -0.3048)
			(stroke
				(width 0.1)
				(type default)
			)
			(layer "B.Fab")
		)
		(fp_line
			(start 0.12065 -0.2794)
			(end -0.12065 -0.2794)
			(stroke
				(width 0.1)
				(type default)
			)
			(layer "B.Fab")
		)
		(fp_line
			(start -0.67945 -0.3048)
			(end -0.67945 0.3048)
			(stroke
				(width 0.1)
				(type default)
			)
			(layer "B.Fab")
		)
		(fp_line
			(start -0.12065 -0.3048)
			(end -0.67945 -0.3048)
			(stroke
				(width 0.1)
				(type default)
			)
			(layer "B.Fab")
		)
		(fp_line
			(start 0.12065 -0.305054)
			(end 0.12065 -0.2794)
			(stroke
				(width 0.1)
				(type default)
			)
			(layer "B.Fab")
		)
		(fp_line
			(start 0.67945 -0.305054)
			(end 0.12065 -0.305054)
			(stroke
				(width 0.1)
				(type default)
			)
			(layer "B.Fab")
		)
		(pad "1" smd circle
			(at 0.40005 0 90)
			(size 0 0)
			(layers "B.Cu" "B.Mask" "B.Paste")
			(net "PVDDCR_CPU1_P0_PVCC")
		)
		(pad "2" smd circle
			(at -0.40005 0 90)
			(size 0 0)
			(layers "B.Cu" "B.Mask" "B.Paste")
			(net "PVDDCR_CPU1_P0_VCC5")
		)
	)
	(footprint ""
		(layer "B.Cu")
		(at 310.578246 -395.148562 90)
		(property "Reference" "C520"
			(at 0 0 90)
			(layer "B.SilkS")
			(hide yes)
			(effects
				(font
					(size 1.27 1.27)
				)
				(justify mirror)
			)
		)
		(property "Value" ""
			(at 0 0 90)
			(layer "B.Fab")
			(effects
				(font
					(size 1.27 1.27)
				)
				(justify mirror)
			)
		)
		(duplicate_pad_numbers_are_jumpers no)
		(fp_line
			(start 0.299974 -0.150114)
			(end -0.299974 -0.150114)
			(stroke
				(width 0.1)
				(type default)
			)
			(layer "B.Fab")
		)
		(fp_line
			(start -0.299974 -0.150114)
			(end -0.299974 0.150114)
			(stroke
				(width 0.1)
				(type default)
			)
			(layer "B.Fab")
		)
		(fp_line
			(start 0.299974 0.150114)
			(end 0.299974 -0.150114)
			(stroke
				(width 0.1)
				(type default)
			)
			(layer "B.Fab")
		)
		(fp_line
			(start -0.299974 0.150114)
			(end 0.299974 0.150114)
			(stroke
				(width 0.1)
				(type default)
			)
			(layer "B.Fab")
		)
		(pad "1" smd rect
			(at 0.2667 0 270)
			(size 0.3048 0.381)
			(layers "B.Cu" "B.Mask" "B.Paste")
			(net "P1V8_CPU0_RT0_1A")
		)
		(pad "2" smd rect
			(at -0.2667 0 270)
			(size 0.3048 0.381)
			(layers "B.Cu" "B.Mask" "B.Paste")
			(net "GND")
		)
	)
	(footprint ""
		(layer "B.Cu")
		(at 150.606252 -386.766562 90)
		(property "Reference" "C389"
			(at 0 0 90)
			(layer "B.SilkS")
			(hide yes)
			(effects
				(font
					(size 1.27 1.27)
				)
				(justify mirror)
			)
		)
		(property "Value" ""
			(at 0 0 90)
			(layer "B.Fab")
			(effects
				(font
					(size 1.27 1.27)
				)
				(justify mirror)
			)
		)
		(duplicate_pad_numbers_are_jumpers no)
		(fp_line
			(start 0.299974 -0.150114)
			(end -0.299974 -0.150114)
			(stroke
				(width 0.1)
				(type default)
			)
			(layer "B.Fab")
		)
		(fp_line
			(start -0.299974 -0.150114)
			(end -0.299974 0.150114)
			(stroke
				(width 0.1)
				(type default)
			)
			(layer "B.Fab")
		)
		(fp_line
			(start 0.299974 0.150114)
			(end 0.299974 -0.150114)
			(stroke
				(width 0.1)
				(type default)
			)
			(layer "B.Fab")
		)
		(fp_line
			(start -0.299974 0.150114)
			(end 0.299974 0.150114)
			(stroke
				(width 0.1)
				(type default)
			)
			(layer "B.Fab")
		)
		(pad "1" smd rect
			(at 0.2667 0 270)
			(size 0.3048 0.381)
			(layers "B.Cu" "B.Mask" "B.Paste")
			(net "P0V9_CPU1_RT2_2A")
		)
		(pad "2" smd rect
			(at -0.2667 0 270)
			(size 0.3048 0.381)
			(layers "B.Cu" "B.Mask" "B.Paste")
			(net "GND")
		)
	)
	(footprint ""
		(layer "B.Cu")
		(at 50.718974 -419.723316 180)
		(property "Reference" "R5236"
			(at 0 0 0)
			(layer "B.SilkS")
			(hide yes)
			(effects
				(font
					(size 1.27 1.27)
				)
				(justify mirror)
			)
		)
		(property "Value" ""
			(at 0 0 0)
			(layer "B.Fab")
			(effects
				(font
					(size 1.27 1.27)
				)
				(justify mirror)
			)
		)
		(duplicate_pad_numbers_are_jumpers no)
		(fp_line
			(start 0.7874 0.4064)
			(end 0.7874 -0.4064)
			(stroke
				(width 0.1524)
				(type default)
			)
			(layer "B.SilkS")
		)
		(fp_line
			(start 0.7874 -0.4064)
			(end -0.7874 -0.4064)
			(stroke
				(width 0.1524)
				(type default)
			)
			(layer "B.SilkS")
		)
		(fp_line
			(start -0.7874 0.4064)
			(end 0.7874 0.4064)
			(stroke
				(width 0.1524)
				(type default)
			)
			(layer "B.SilkS")
		)
		(fp_line
			(start -0.7874 -0.4064)
			(end -0.7874 0.4064)
			(stroke
				(width 0.1524)
				(type default)
			)
			(layer "B.SilkS")
		)
		(fp_line
			(start 0.67945 0.3048)
			(end 0.67945 -0.305054)
			(stroke
				(width 0.1)
				(type default)
			)
			(layer "B.Fab")
		)
		(fp_line
			(start 0.67945 -0.305054)
			(end 0.12065 -0.305054)
			(stroke
				(width 0.1)
				(type default)
			)
			(layer "B.Fab")
		)
		(fp_line
			(start 0.12065 0.3048)
			(end 0.67945 0.3048)
			(stroke
				(width 0.1)
				(type default)
			)
			(layer "B.Fab")
		)
		(fp_line
			(start 0.12065 0.2794)
			(end 0.12065 0.3048)
			(stroke
				(width 0.1)
				(type default)
			)
			(layer "B.Fab")
		)
		(fp_line
			(start 0.12065 -0.2794)
			(end -0.12065 -0.2794)
			(stroke
				(width 0.1)
				(type default)
			)
			(layer "B.Fab")
		)
		(fp_line
			(start 0.12065 -0.305054)
			(end 0.12065 -0.2794)
			(stroke
				(width 0.1)
				(type default)
			)
			(layer "B.Fab")
		)
		(fp_line
			(start -0.120396 0.3048)
			(end -0.120396 0.2794)
			(stroke
				(width 0.1)
				(type default)
			)
			(layer "B.Fab")
		)
		(fp_line
			(start -0.120396 0.2794)
			(end 0.12065 0.2794)
			(stroke
				(width 0.1)
				(type default)
			)
			(layer "B.Fab")
		)
		(fp_line
			(start -0.12065 -0.2794)
			(end -0.12065 -0.3048)
			(stroke
				(width 0.1)
				(type default)
			)
			(layer "B.Fab")
		)
		(fp_line
			(start -0.12065 -0.3048)
			(end -0.67945 -0.3048)
			(stroke
				(width 0.1)
				(type default)
			)
			(layer "B.Fab")
		)
		(fp_line
			(start -0.67945 0.3048)
			(end -0.120396 0.3048)
			(stroke
				(width 0.1)
				(type default)
			)
			(layer "B.Fab")
		)
		(fp_line
			(start -0.67945 -0.3048)
			(end -0.67945 0.3048)
			(stroke
				(width 0.1)
				(type default)
			)
			(layer "B.Fab")
		)
		(pad "1" smd circle
			(at 0.40005 0)
			(size 0 0)
			(layers "B.Cu" "B.Mask" "B.Paste")
			(net "USB2_HUB_BUF_SWB_R_DN")
		)
		(pad "2" smd circle
			(at -0.40005 0)
			(size 0 0)
			(layers "B.Cu" "B.Mask" "B.Paste")
			(net "USB2_HUB_BUF_SWB_DN")
		)
	)
	(footprint ""
		(layer "B.Cu")
		(at 180.681376 -133.053328 90)
		(property "Reference" "R203"
			(at 0 0 90)
			(layer "B.SilkS")
			(hide yes)
			(effects
				(font
					(size 1.27 1.27)
				)
				(justify mirror)
			)
		)
		(property "Value" ""
			(at 0 0 90)
			(layer "B.Fab")
			(effects
				(font
					(size 1.27 1.27)
				)
				(justify mirror)
			)
		)
		(duplicate_pad_numbers_are_jumpers no)
		(fp_line
			(start 0.7874 -0.4064)
			(end -0.7874 -0.4064)
			(stroke
				(width 0.1524)
				(type default)
			)
			(layer "B.SilkS")
		)
		(fp_line
			(start -0.7874 -0.4064)
			(end -0.7874 0.4064)
			(stroke
				(width 0.1524)
				(type default)
			)
			(layer "B.SilkS")
		)
		(fp_line
			(start 0.7874 0.4064)
			(end 0.7874 -0.4064)
			(stroke
				(width 0.1524)
				(type default)
			)
			(layer "B.SilkS")
		)
		(fp_line
			(start -0.7874 0.4064)
			(end 0.7874 0.4064)
			(stroke
				(width 0.1524)
				(type default)
			)
			(layer "B.SilkS")
		)
		(fp_line
			(start 0.67945 -0.305054)
			(end 0.12065 -0.305054)
			(stroke
				(width 0.1)
				(type default)
			)
			(layer "B.Fab")
		)
		(fp_line
			(start 0.12065 -0.305054)
			(end 0.12065 -0.2794)
			(stroke
				(width 0.1)
				(type default)
			)
			(layer "B.Fab")
		)
		(fp_line
			(start -0.12065 -0.3048)
			(end -0.67945 -0.3048)
			(stroke
				(width 0.1)
				(type default)
			)
			(layer "B.Fab")
		)
		(fp_line
			(start -0.67945 -0.3048)
			(end -0.67945 0.3048)
			(stroke
				(width 0.1)
				(type default)
			)
			(layer "B.Fab")
		)
		(fp_line
			(start 0.12065 -0.2794)
			(end -0.12065 -0.2794)
			(stroke
				(width 0.1)
				(type default)
			)
			(layer "B.Fab")
		)
		(fp_line
			(start -0.12065 -0.2794)
			(end -0.12065 -0.3048)
			(stroke
				(width 0.1)
				(type default)
			)
			(layer "B.Fab")
		)
		(fp_line
			(start 0.12065 0.2794)
			(end 0.12065 0.3048)
			(stroke
				(width 0.1)
				(type default)
			)
			(layer "B.Fab")
		)
		(fp_line
			(start -0.120396 0.2794)
			(end 0.12065 0.2794)
			(stroke
				(width 0.1)
				(type default)
			)
			(layer "B.Fab")
		)
		(fp_line
			(start 0.67945 0.3048)
			(end 0.67945 -0.305054)
			(stroke
				(width 0.1)
				(type default)
			)
			(layer "B.Fab")
		)
		(fp_line
			(start 0.12065 0.3048)
			(end 0.67945 0.3048)
			(stroke
				(width 0.1)
				(type default)
			)
			(layer "B.Fab")
		)
		(fp_line
			(start -0.120396 0.3048)
			(end -0.120396 0.2794)
			(stroke
				(width 0.1)
				(type default)
			)
			(layer "B.Fab")
		)
		(fp_line
			(start -0.67945 0.3048)
			(end -0.120396 0.3048)
			(stroke
				(width 0.1)
				(type default)
			)
			(layer "B.Fab")
		)
		(pad "1" smd circle
			(at 0.40005 0 270)
			(size 0 0)
			(layers "B.Cu" "B.Mask" "B.Paste")
			(net "PWRGD_CPU1_PWROK")
		)
		(pad "2" smd circle
			(at -0.40005 0 270)
			(size 0 0)
			(layers "B.Cu" "B.Mask" "B.Paste")
			(net "FM_PWRGD_CPU1_PWROK")
		)
	)
	(footprint ""
		(layer "B.Cu")
		(at 186.345322 -13.60043 -90)
		(property "Reference" "R6004"
			(at 0 0 90)
			(layer "B.SilkS")
			(hide yes)
			(effects
				(font
					(size 1.27 1.27)
				)
				(justify mirror)
			)
		)
		(property "Value" ""
			(at 0 0 90)
			(layer "B.Fab")
			(effects
				(font
					(size 1.27 1.27)
				)
				(justify mirror)
			)
		)
		(duplicate_pad_numbers_are_jumpers no)
		(fp_line
			(start -0.7874 0.4064)
			(end 0.7874 0.4064)
			(stroke
				(width 0.1524)
				(type default)
			)
			(layer "B.SilkS")
		)
		(fp_line
			(start 0.7874 0.4064)
			(end 0.7874 -0.4064)
			(stroke
				(width 0.1524)
				(type default)
			)
			(layer "B.SilkS")
		)
		(fp_line
			(start -0.7874 -0.4064)
			(end -0.7874 0.4064)
			(stroke
				(width 0.1524)
				(type default)
			)
			(layer "B.SilkS")
		)
		(fp_line
			(start 0.7874 -0.4064)
			(end -0.7874 -0.4064)
			(stroke
				(width 0.1524)
				(type default)
			)
			(layer "B.SilkS")
		)
		(fp_line
			(start -0.67945 0.3048)
			(end -0.120396 0.3048)
			(stroke
				(width 0.1)
				(type default)
			)
			(layer "B.Fab")
		)
		(fp_line
			(start -0.120396 0.3048)
			(end -0.120396 0.2794)
			(stroke
				(width 0.1)
				(type default)
			)
			(layer "B.Fab")
		)
		(fp_line
			(start 0.12065 0.3048)
			(end 0.67945 0.3048)
			(stroke
				(width 0.1)
				(type default)
			)
			(layer "B.Fab")
		)
		(fp_line
			(start 0.67945 0.3048)
			(end 0.67945 -0.305054)
			(stroke
				(width 0.1)
				(type default)
			)
			(layer "B.Fab")
		)
		(fp_line
			(start -0.120396 0.2794)
			(end 0.12065 0.2794)
			(stroke
				(width 0.1)
				(type default)
			)
			(layer "B.Fab")
		)
		(fp_line
			(start 0.12065 0.2794)
			(end 0.12065 0.3048)
			(stroke
				(width 0.1)
				(type default)
			)
			(layer "B.Fab")
		)
		(fp_line
			(start -0.12065 -0.2794)
			(end -0.12065 -0.3048)
			(stroke
				(width 0.1)
				(type default)
			)
			(layer "B.Fab")
		)
		(fp_line
			(start 0.12065 -0.2794)
			(end -0.12065 -0.2794)
			(stroke
				(width 0.1)
				(type default)
			)
			(layer "B.Fab")
		)
		(fp_line
			(start -0.67945 -0.3048)
			(end -0.67945 0.3048)
			(stroke
				(width 0.1)
				(type default)
			)
			(layer "B.Fab")
		)
		(fp_line
			(start -0.12065 -0.3048)
			(end -0.67945 -0.3048)
			(stroke
				(width 0.1)
				(type default)
			)
			(layer "B.Fab")
		)
		(fp_line
			(start 0.12065 -0.305054)
			(end 0.12065 -0.2794)
			(stroke
				(width 0.1)
				(type default)
			)
			(layer "B.Fab")
		)
		(fp_line
			(start 0.67945 -0.305054)
			(end 0.12065 -0.305054)
			(stroke
				(width 0.1)
				(type default)
			)
			(layer "B.Fab")
		)
		(pad "1" smd circle
			(at 0.40005 0 90)
			(size 0 0)
			(layers "B.Cu" "B.Mask" "B.Paste")
			(net "I3C_SCM_2_SCL")
		)
		(pad "2" smd circle
			(at -0.40005 0 90)
			(size 0 0)
			(layers "B.Cu" "B.Mask" "B.Paste")
			(net "I3C_SCM_2_R_SCL")
		)
	)
	(footprint ""
		(layer "B.Cu")
		(at 415.018982 -399.291302 90)
		(property "Reference" "C980"
			(at 0 0 90)
			(layer "B.SilkS")
			(hide yes)
			(effects
				(font
					(size 1.27 1.27)
				)
				(justify mirror)
			)
		)
		(property "Value" ""
			(at 0 0 90)
			(layer "B.Fab")
			(effects
				(font
					(size 1.27 1.27)
				)
				(justify mirror)
			)
		)
		(duplicate_pad_numbers_are_jumpers no)
		(fp_line
			(start 0.299974 -0.150114)
			(end -0.299974 -0.150114)
			(stroke
				(width 0.1)
				(type default)
			)
			(layer "B.Fab")
		)
		(fp_line
			(start -0.299974 -0.150114)
			(end -0.299974 0.150114)
			(stroke
				(width 0.1)
				(type default)
			)
			(layer "B.Fab")
		)
		(fp_line
			(start 0.299974 0.150114)
			(end 0.299974 -0.150114)
			(stroke
				(width 0.1)
				(type default)
			)
			(layer "B.Fab")
		)
		(fp_line
			(start -0.299974 0.150114)
			(end 0.299974 0.150114)
			(stroke
				(width 0.1)
				(type default)
			)
			(layer "B.Fab")
		)
		(pad "1" smd rect
			(at 0.2667 0 270)
			(size 0.3048 0.381)
			(layers "B.Cu" "B.Mask" "B.Paste")
			(net "P0V9_CPU0_RT_2D")
		)
		(pad "2" smd rect
			(at -0.2667 0 270)
			(size 0.3048 0.381)
			(layers "B.Cu" "B.Mask" "B.Paste")
			(net "GND")
		)
	)
)
